(kicad_pcb
	(version 20241229)
	(generator "pcbnew")
	(generator_version "9.0")
	(general
		(thickness 1.711)
		(legacy_teardrops no)
	)
	(paper "A4")
	(title_block
		(title "Antmicro Baseboard for Jetson AGX Thor")
		(date "2026-02-18")
		(rev "1.1.0")
		(company "Antmicro Ltd")
		(comment 1 "www.antmicro.com")
		(comment 9 "footprints 803-808 of 1170")
	)
	(layers
		(0 "F.Cu" signal)
		(4 "In1.Cu" signal)
		(6 "In2.Cu" signal)
		(8 "In3.Cu" signal)
		(10 "In4.Cu" jumper)
		(12 "In5.Cu" signal)
		(14 "In6.Cu" signal)
		(16 "In7.Cu" signal)
		(18 "In8.Cu" signal)
		(2 "B.Cu" signal)
		(9 "F.Adhes" user "F.Adhesive")
		(11 "B.Adhes" user "B.Adhesive")
		(13 "F.Paste" user)
		(15 "B.Paste" user)
		(5 "F.SilkS" user "F.Silkscreen")
		(7 "B.SilkS" user "B.Silkscreen")
		(1 "F.Mask" user)
		(3 "B.Mask" user)
		(17 "Dwgs.User" user "User.Drawings")
		(19 "Cmts.User" user "User.Comments")
		(21 "Eco1.User" user "User.Eco1")
		(23 "Eco2.User" user "User.Eco2")
		(25 "Edge.Cuts" user)
		(27 "Margin" user)
		(31 "F.CrtYd" user "F.Courtyard")
		(29 "B.CrtYd" user "B.Courtyard")
		(35 "F.Fab" user)
		(33 "B.Fab" user)
	)
	(footprint "antmicro-footprints:SOD-523"
		(layer "B.Cu")
		(at 221.98 123.9 90)
		(property "Reference" "D59"
			(at -3.1 0.5 90)
			(layer "B.SilkS")
			(effects
				(font
					(size 0.7 0.7)
					(thickness 0.15)
				)
				(justify right top mirror)
			)
		)
		(property "Value" "RB521S30T1G"
			(at 0 -1.499 90)
			(layer "B.Fab")
			(effects
				(font
					(size 0.7 0.7)
					(thickness 0.15)
				)
				(justify right top mirror)
			)
		)
		(property "Datasheet" "https://www.onsemi.com/pdf/datasheet/rb521s30t1-d.pdf"
			(at 0 0 90)
			(layer "B.Fab")
			(hide yes)
			(effects
				(font
					(size 1.27 1.27)
					(thickness 0.15)
				)
				(justify mirror)
			)
		)
		(property "Description" "Small Signal Schottky Diode, Single, 30 V, 200 mA, 500 mV, 1 A, 125 °C"
			(at 0 0 90)
			(layer "B.Fab")
			(hide yes)
			(effects
				(font
					(size 1.27 1.27)
					(thickness 0.15)
				)
				(justify mirror)
			)
		)
		(property "MPN" "RB521S30T1G"
			(at 0 0 270)
			(unlocked yes)
			(layer "B.Fab")
			(hide yes)
			(effects
				(font
					(size 1 1)
					(thickness 0.15)
				)
				(justify mirror)
			)
		)
		(property "Manufacturer" "ON Semiconductor"
			(at 0 0 270)
			(unlocked yes)
			(layer "B.Fab")
			(hide yes)
			(effects
				(font
					(size 1 1)
					(thickness 0.15)
				)
				(justify mirror)
			)
		)
		(property "Author" "Antmicro"
			(at 0 0 270)
			(unlocked yes)
			(layer "B.Fab")
			(hide yes)
			(effects
				(font
					(size 1 1)
					(thickness 0.15)
				)
				(justify mirror)
			)
		)
		(property "License" "Apache-2.0"
			(at 0 0 270)
			(unlocked yes)
			(layer "B.Fab")
			(hide yes)
			(effects
				(font
					(size 1 1)
					(thickness 0.15)
				)
				(justify mirror)
			)
		)
		(sheetname "/USB Hub/")
		(sheetfile "usb_hub.kicad_sch")
		(attr smd)
		(fp_line
			(start -0.35 0.5)
			(end -0.35 -0.5)
			(stroke
				(width 0.15)
				(type solid)
			)
			(layer "B.SilkS")
		)
		(fp_rect
			(start -1 0.6)
			(end 1 -0.6)
			(stroke
				(width 0.05)
				(type solid)
			)
			(fill no)
			(layer "B.CrtYd")
		)
		(fp_line
			(start -0.652 -0.423)
			(end 0.65 -0.423)
			(stroke
				(width 0.15)
				(type solid)
			)
			(layer "B.Fab")
		)
		(fp_line
			(start -0.652 -0.423)
			(end -0.652 0.425)
			(stroke
				(width 0.15)
				(type solid)
			)
			(layer "B.Fab")
		)
		(fp_line
			(start -0.35 0.4)
			(end -0.35 -0.4)
			(stroke
				(width 0.15)
				(type solid)
			)
			(layer "B.Fab")
		)
		(fp_line
			(start 0.65 0.425)
			(end 0.65 -0.423)
			(stroke
				(width 0.15)
				(type solid)
			)
			(layer "B.Fab")
		)
		(fp_line
			(start -0.652 0.425)
			(end 0.65 0.425)
			(stroke
				(width 0.15)
				(type solid)
			)
			(layer "B.Fab")
		)
		(fp_text user "${REFERENCE}"
			(at -1.276 -3.499 90)
			(layer "B.Fab")
			(effects
				(font
					(size 0.7 0.7)
					(thickness 0.15)
				)
				(justify right top mirror)
			)
		)
		(fp_text user "License: Apache-2.0"
			(at -1.276 -5.9 90)
			(layer "B.Fab")
			(effects
				(font
					(size 0.7 0.7)
					(thickness 0.15)
				)
				(justify right top mirror)
			)
		)
		(fp_text user "Author: Antmicro"
			(at -1.276 -4.7 90)
			(layer "B.Fab")
			(effects
				(font
					(size 0.7 0.7)
					(thickness 0.15)
				)
				(justify right top mirror)
			)
		)
		(pad "1" smd roundrect
			(at -0.701 0 90)
			(size 0.5 0.6)
			(layers "B.Cu" "B.Mask" "B.Paste")
			(roundrect_rratio 0.25)
			(net 1238 "Net-(D59-C)")
			(pinfunction "C")
			(pintype "passive")
		)
		(pad "2" smd roundrect
			(at 0.699 0 90)
			(size 0.5 0.6)
			(layers "B.Cu" "B.Mask" "B.Paste")
			(roundrect_rratio 0.25)
			(net 1239 "Net-(D59-A)")
			(pinfunction "A")
			(pintype "passive")
		)
	)
	(footprint "antmicro-footprints:R_0402_1005Metric"
		(layer "B.Cu")
		(at 67.4 65.7 -90)
		(descr "Resistor SMD 0402")
		(tags "resistor SMD 0402")
		(property "Reference" "R393"
			(at 0.9 -0.5 90)
			(layer "B.SilkS")
			(effects
				(font
					(size 0.7 0.7)
					(thickness 0.15)
				)
				(justify left bottom mirror)
			)
		)
		(property "Value" "R_2k2_0402"
			(at -1.011843 -1.772047 90)
			(layer "B.Fab")
			(effects
				(font
					(size 0.7 0.7)
					(thickness 0.15)
				)
				(justify left bottom mirror)
			)
		)
		(property "Datasheet" "https://www.bourns.com/docs/product-datasheets/cr.pdf"
			(at 0 0 90)
			(layer "B.Fab")
			(hide yes)
			(effects
				(font
					(size 1.27 1.27)
					(thickness 0.15)
				)
				(justify mirror)
			)
		)
		(property "Description" "SMD Chip Resistor, 2.2 kohm, ± 1%, 62.5 mW, 0402 [1005 Metric], Thick Film, General Purpose"
			(at 0 0 90)
			(layer "B.Fab")
			(hide yes)
			(effects
				(font
					(size 1.27 1.27)
					(thickness 0.15)
				)
				(justify mirror)
			)
		)
		(property "MPN" "CR0402-FX-2201GLF"
			(at 0 0 90)
			(unlocked yes)
			(layer "B.Fab")
			(hide yes)
			(effects
				(font
					(size 1 1)
					(thickness 0.15)
				)
				(justify mirror)
			)
		)
		(property "Manufacturer" "Bourns"
			(at 0 0 90)
			(unlocked yes)
			(layer "B.Fab")
			(hide yes)
			(effects
				(font
					(size 1 1)
					(thickness 0.15)
				)
				(justify mirror)
			)
		)
		(property "License" "Apache-2.0"
			(at 0 0 90)
			(unlocked yes)
			(layer "B.Fab")
			(hide yes)
			(effects
				(font
					(size 1 1)
					(thickness 0.15)
				)
				(justify mirror)
			)
		)
		(property "Author" "Antmicro"
			(at 0 0 90)
			(unlocked yes)
			(layer "B.Fab")
			(hide yes)
			(effects
				(font
					(size 1 1)
					(thickness 0.15)
				)
				(justify mirror)
			)
		)
		(property "Val" "2k2"
			(at 0 0 90)
			(unlocked yes)
			(layer "B.Fab")
			(hide yes)
			(effects
				(font
					(size 1 1)
					(thickness 0.15)
				)
				(justify mirror)
			)
		)
		(property "Tolerance" "1%"
			(at 0 0 90)
			(unlocked yes)
			(layer "B.Fab")
			(hide yes)
			(effects
				(font
					(size 1 1)
					(thickness 0.15)
				)
				(justify mirror)
			)
		)
		(sheetname "/CSI/")
		(sheetfile "csi.kicad_sch")
		(attr smd)
		(fp_rect
			(start -0.925 0.47)
			(end 0.925 -0.47)
			(stroke
				(width 0.05)
				(type default)
			)
			(fill no)
			(layer "B.CrtYd")
		)
		(fp_rect
			(start -0.5 0.25)
			(end 0.5 -0.25)
			(stroke
				(width 0.15)
				(type solid)
			)
			(fill no)
			(layer "B.Fab")
		)
		(fp_text user "License: Apache-2.0"
			(at -0.95 -5.169 90)
			(layer "B.Fab")
			(effects
				(font
					(size 0.7 0.7)
					(thickness 0.15)
				)
				(justify left bottom mirror)
			)
		)
		(fp_text user "Author: Antmicro"
			(at -0.95 -4.169 90)
			(layer "B.Fab")
			(effects
				(font
					(size 0.7 0.7)
					(thickness 0.15)
				)
				(justify left bottom mirror)
			)
		)
		(fp_text user "${REFERENCE}"
			(at -0.95 -3.168 90)
			(layer "B.Fab")
			(effects
				(font
					(size 0.7 0.7)
					(thickness 0.15)
				)
				(justify left bottom mirror)
			)
		)
		(pad "1" smd roundrect
			(at -0.48 0 270)
			(size 0.59 0.64)
			(layers "B.Cu" "B.Mask" "B.Paste")
			(roundrect_rratio 0.25)
			(net 990 "/CSI/CSIB_I2C_VCC")
			(pintype "passive")
		)
		(pad "2" smd roundrect
			(at 0.48 0 270)
			(size 0.59 0.64)
			(layers "B.Cu" "B.Mask" "B.Paste")
			(roundrect_rratio 0.25)
			(net 991 "/CSI/SDA_CAM3")
			(pintype "passive")
		)
	)
	(footprint "antmicro-footprints:R_0402_1005Metric"
		(layer "B.Cu")
		(at 214.9 95.1 -90)
		(descr "Resistor SMD 0402")
		(tags "resistor SMD 0402")
		(property "Reference" "R118"
			(at 1 -0.4 90)
			(layer "B.SilkS")
			(effects
				(font
					(size 0.7 0.7)
					(thickness 0.15)
				)
				(justify left bottom mirror)
			)
		)
		(property "Value" "R_0R_0402"
			(at -1.011843 -1.772046 90)
			(layer "B.Fab")
			(effects
				(font
					(size 0.7 0.7)
					(thickness 0.15)
				)
				(justify left bottom mirror)
			)
		)
		(property "Datasheet" "https://industrial.panasonic.com/cdbs/www-data/pdf/RDA0000/AOA0000C301.pdf"
			(at 0 0 90)
			(layer "B.Fab")
			(hide yes)
			(effects
				(font
					(size 1.27 1.27)
					(thickness 0.15)
				)
				(justify mirror)
			)
		)
		(property "Description" "SMD Chip Resistor, Jumper, 0 ohm, 100 mW, 0402 [1005 Metric], Thick Film, General Purpose"
			(at 0 0 90)
			(layer "B.Fab")
			(hide yes)
			(effects
				(font
					(size 1.27 1.27)
					(thickness 0.15)
				)
				(justify mirror)
			)
		)
		(property "Manufacturer" "Panasonic"
			(at 0 0 90)
			(unlocked yes)
			(layer "B.Fab")
			(hide yes)
			(effects
				(font
					(size 1 1)
					(thickness 0.15)
				)
				(justify mirror)
			)
		)
		(property "MPN" "ERJ2GE0R00X"
			(at 0 0 90)
			(unlocked yes)
			(layer "B.Fab")
			(hide yes)
			(effects
				(font
					(size 1 1)
					(thickness 0.15)
				)
				(justify mirror)
			)
		)
		(property "Val" "0R"
			(at 0 0 90)
			(unlocked yes)
			(layer "B.Fab")
			(hide yes)
			(effects
				(font
					(size 1 1)
					(thickness 0.15)
				)
				(justify mirror)
			)
		)
		(property "License" "Apache-2.0"
			(at 0 0 90)
			(unlocked yes)
			(layer "B.Fab")
			(hide yes)
			(effects
				(font
					(size 1 1)
					(thickness 0.15)
				)
				(justify mirror)
			)
		)
		(property "Author" "Antmicro"
			(at 0 0 90)
			(unlocked yes)
			(layer "B.Fab")
			(hide yes)
			(effects
				(font
					(size 1 1)
					(thickness 0.15)
				)
				(justify mirror)
			)
		)
		(property "Tolerance" "~"
			(at 0 0 90)
			(unlocked yes)
			(layer "B.Fab")
			(hide yes)
			(effects
				(font
					(size 1 1)
					(thickness 0.15)
				)
				(justify mirror)
			)
		)
		(property "Current" "1A"
			(at 0 0 90)
			(unlocked yes)
			(layer "B.Fab")
			(hide yes)
			(effects
				(font
					(size 1 1)
					(thickness 0.15)
				)
				(justify mirror)
			)
		)
		(sheetname "/USB DP Alt mode/")
		(sheetfile "usb_dp.kicad_sch")
		(attr smd)
		(fp_poly
			(pts
				(xy -0.925 0.47) (xy -0.925 -0.47) (xy 0.925 -0.47) (xy 0.925 0.47)
			)
			(stroke
				(width 0.05)
				(type default)
			)
			(fill no)
			(layer "B.CrtYd")
		)
		(fp_poly
			(pts
				(xy -0.5 0.25) (xy -0.5 -0.25) (xy 0.5 -0.25) (xy 0.5 0.25)
			)
			(stroke
				(width 0.15)
				(type solid)
			)
			(fill no)
			(layer "B.Fab")
		)
		(fp_text user "Author: Antmicro"
			(at -0.95 -4.169 90)
			(layer "B.Fab")
			(effects
				(font
					(size 0.7 0.7)
					(thickness 0.15)
				)
				(justify left bottom mirror)
			)
		)
		(fp_text user "${REFERENCE}"
			(at -0.95 -3.168 90)
			(layer "B.Fab")
			(effects
				(font
					(size 0.7 0.7)
					(thickness 0.15)
				)
				(justify left bottom mirror)
			)
		)
		(fp_text user "License: Apache-2.0"
			(at -0.949999 -5.169 90)
			(layer "B.Fab")
			(effects
				(font
					(size 0.7 0.7)
					(thickness 0.15)
				)
				(justify left bottom mirror)
			)
		)
		(pad "1" smd roundrect
			(at -0.48 0 270)
			(size 0.59 0.64)
			(layers "B.Cu" "B.Mask" "B.Paste")
			(roundrect_rratio 0.25)
			(net 788 "/SoM_IO2/DP0.HPD")
			(pintype "passive")
		)
		(pad "2" smd roundrect
			(at 0.48 0 270)
			(size 0.59 0.64)
			(layers "B.Cu" "B.Mask" "B.Paste")
			(roundrect_rratio 0.25)
			(net 1301 "Net-(Q35-D)")
			(pintype "passive")
		)
	)
	(footprint "antmicro-footprints:R_0402_1005Metric"
		(layer "B.Cu")
		(at 207.8 79.3 180)
		(descr "Resistor SMD 0402")
		(tags "resistor SMD 0402")
		(property "Reference" "R95"
			(at -3.1 -0.425 0)
			(layer "B.SilkS")
			(effects
				(font
					(size 0.7 0.7)
					(thickness 0.15)
				)
				(justify left bottom mirror)
			)
		)
		(property "Value" "R_100k_0402"
			(at -1.011843 -1.772047 0)
			(layer "B.Fab")
			(effects
				(font
					(size 0.7 0.7)
					(thickness 0.15)
				)
				(justify left bottom mirror)
			)
		)
		(property "Datasheet" "https://www.bourns.com/docs/product-datasheets/cr.pdf"
			(at 0 0 0)
			(layer "B.Fab")
			(hide yes)
			(effects
				(font
					(size 1.27 1.27)
					(thickness 0.15)
				)
				(justify mirror)
			)
		)
		(property "Description" "SMD Chip Resistor, 100 kohm, ± 1%, 62.5 mW, 0402 [1005 Metric], Thick Film, General Purpose"
			(at 0 0 0)
			(layer "B.Fab")
			(hide yes)
			(effects
				(font
					(size 1.27 1.27)
					(thickness 0.15)
				)
				(justify mirror)
			)
		)
		(property "Manufacturer" "Bourns"
			(at 0 0 0)
			(unlocked yes)
			(layer "B.Fab")
			(hide yes)
			(effects
				(font
					(size 1 1)
					(thickness 0.15)
				)
				(justify mirror)
			)
		)
		(property "MPN" "CR0402-FX-1003GLF"
			(at 0 0 0)
			(unlocked yes)
			(layer "B.Fab")
			(hide yes)
			(effects
				(font
					(size 1 1)
					(thickness 0.15)
				)
				(justify mirror)
			)
		)
		(property "Val" "100k"
			(at 0 0 0)
			(unlocked yes)
			(layer "B.Fab")
			(hide yes)
			(effects
				(font
					(size 1 1)
					(thickness 0.15)
				)
				(justify mirror)
			)
		)
		(property "License" "Apache-2.0"
			(at 0 0 0)
			(unlocked yes)
			(layer "B.Fab")
			(hide yes)
			(effects
				(font
					(size 1 1)
					(thickness 0.15)
				)
				(justify mirror)
			)
		)
		(property "Author" "Antmicro"
			(at 0 0 0)
			(unlocked yes)
			(layer "B.Fab")
			(hide yes)
			(effects
				(font
					(size 1 1)
					(thickness 0.15)
				)
				(justify mirror)
			)
		)
		(property "Tolerance" "1%"
			(at 0 0 0)
			(unlocked yes)
			(layer "B.Fab")
			(hide yes)
			(effects
				(font
					(size 1 1)
					(thickness 0.15)
				)
				(justify mirror)
			)
		)
		(sheetname "/USB Debug, PD/")
		(sheetfile "usb_debug_pd.kicad_sch")
		(attr smd)
		(fp_rect
			(start -0.925 0.47)
			(end 0.925 -0.47)
			(stroke
				(width 0.05)
				(type default)
			)
			(fill no)
			(layer "B.CrtYd")
		)
		(fp_rect
			(start -0.5 0.25)
			(end 0.5 -0.25)
			(stroke
				(width 0.15)
				(type solid)
			)
			(fill no)
			(layer "B.Fab")
		)
		(fp_text user "License: Apache-2.0"
			(at -0.95 -5.169 0)
			(layer "B.Fab")
			(effects
				(font
					(size 0.7 0.7)
					(thickness 0.15)
				)
				(justify left bottom mirror)
			)
		)
		(fp_text user "Author: Antmicro"
			(at -0.95 -4.169 0)
			(layer "B.Fab")
			(effects
				(font
					(size 0.7 0.7)
					(thickness 0.15)
				)
				(justify left bottom mirror)
			)
		)
		(fp_text user "${REFERENCE}"
			(at -0.95 -3.168 0)
			(layer "B.Fab")
			(effects
				(font
					(size 0.7 0.7)
					(thickness 0.15)
				)
				(justify left bottom mirror)
			)
		)
		(pad "1" smd roundrect
			(at -0.48 0 180)
			(size 0.59 0.64)
			(layers "B.Cu" "B.Mask" "B.Paste")
			(roundrect_rratio 0.25)
			(net 294 "/USB Debug, PD/PDC_LDO_3V3")
			(pintype "passive")
		)
		(pad "2" smd roundrect
			(at 0.48 0 180)
			(size 0.59 0.64)
			(layers "B.Cu" "B.Mask" "B.Paste")
			(roundrect_rratio 0.25)
			(net 934 "/USB Debug, PD/PDC_ADCIN1")
			(pintype "passive")
		)
	)
	(footprint "antmicro-footprints:TP_SMD_0.75mm"
		(layer "B.Cu")
		(at 171.89 58 180)
		(property "Reference" "TP129"
			(at -0.42 4.05 90)
			(layer "B.SilkS")
			(effects
				(font
					(size 0.7 0.7)
					(thickness 0.15)
				)
				(justify left bottom mirror)
			)
		)
		(property "Value" "TP_0.75mm_SMD"
			(at 0 -1.2 0)
			(layer "B.Fab")
			(effects
				(font
					(size 0.7 0.7)
					(thickness 0.15)
				)
				(justify left bottom mirror)
			)
		)
		(property "Description" "SMT test point"
			(at 0 0 0)
			(layer "B.Fab")
			(hide yes)
			(effects
				(font
					(size 1.27 1.27)
					(thickness 0.15)
				)
				(justify mirror)
			)
		)
		(property "MPN" ""
			(at 0 0 0)
			(unlocked yes)
			(layer "B.Fab")
			(hide yes)
			(effects
				(font
					(size 1 1)
					(thickness 0.15)
				)
				(justify mirror)
			)
		)
		(property "Manufacturer" ""
			(at 0 0 0)
			(unlocked yes)
			(layer "B.Fab")
			(hide yes)
			(effects
				(font
					(size 1 1)
					(thickness 0.15)
				)
				(justify mirror)
			)
		)
		(property "Author" "Antmicro"
			(at 0 0 0)
			(unlocked yes)
			(layer "B.Fab")
			(hide yes)
			(effects
				(font
					(size 1 1)
					(thickness 0.15)
				)
				(justify mirror)
			)
		)
		(property "License" "Apache-2.0"
			(at 0 0 0)
			(unlocked yes)
			(layer "B.Fab")
			(hide yes)
			(effects
				(font
					(size 1 1)
					(thickness 0.15)
				)
				(justify mirror)
			)
		)
		(sheetname "/Power/")
		(sheetfile "power.kicad_sch")
		(attr exclude_from_pos_files exclude_from_bom)
		(fp_circle
			(center 0 0)
			(end 0.475 0)
			(stroke
				(width 0.05)
				(type default)
			)
			(fill no)
			(layer "B.CrtYd")
		)
		(fp_text user "${REFERENCE}"
			(at -0.4 -2.7 0)
			(layer "B.Fab")
			(effects
				(font
					(size 0.7 0.7)
					(thickness 0.15)
				)
				(justify left bottom mirror)
			)
		)
		(fp_text user "License: Apache-2.0"
			(at -0.4 -5.101 0)
			(layer "B.Fab")
			(effects
				(font
					(size 0.7 0.7)
					(thickness 0.15)
				)
				(justify left bottom mirror)
			)
		)
		(fp_text user "Author: Antmicro"
			(at -0.4 -3.901 0)
			(layer "B.Fab")
			(effects
				(font
					(size 0.7 0.7)
					(thickness 0.15)
				)
				(justify left bottom mirror)
			)
		)
		(pad "1" smd circle
			(at 0 0 180)
			(size 0.75 0.75)
			(layers "B.Cu" "B.Mask")
			(net 5 "+5V")
			(pinfunction "1")
			(pintype "passive")
		)
	)
	(footprint "antmicro-footprints:TP_SMD_0.75mm"
		(layer "B.Cu")
		(at 92.1 60.454 180)
		(property "Reference" "TP117"
			(at -0.59 -0.466 90)
			(layer "B.SilkS")
			(effects
				(font
					(size 0.7 0.7)
					(thickness 0.15)
				)
				(justify left bottom mirror)
			)
		)
		(property "Value" "TP_0.75mm_SMD"
			(at 0 -1.2 0)
			(layer "B.Fab")
			(effects
				(font
					(size 0.7 0.7)
					(thickness 0.15)
				)
				(justify left bottom mirror)
			)
		)
		(property "Description" "SMT test point"
			(at 0 0 0)
			(layer "B.Fab")
			(hide yes)
			(effects
				(font
					(size 1.27 1.27)
					(thickness 0.15)
				)
				(justify mirror)
			)
		)
		(property "MPN" ""
			(at 0 0 0)
			(unlocked yes)
			(layer "B.Fab")
			(hide yes)
			(effects
				(font
					(size 1 1)
					(thickness 0.15)
				)
				(justify mirror)
			)
		)
		(property "Manufacturer" ""
			(at 0 0 0)
			(unlocked yes)
			(layer "B.Fab")
			(hide yes)
			(effects
				(font
					(size 1 1)
					(thickness 0.15)
				)
				(justify mirror)
			)
		)
		(property "Author" "Antmicro"
			(at 0 0 0)
			(unlocked yes)
			(layer "B.Fab")
			(hide yes)
			(effects
				(font
					(size 1 1)
					(thickness 0.15)
				)
				(justify mirror)
			)
		)
		(property "License" "Apache-2.0"
			(at 0 0 0)
			(unlocked yes)
			(layer "B.Fab")
			(hide yes)
			(effects
				(font
					(size 1 1)
					(thickness 0.15)
				)
				(justify mirror)
			)
		)
		(sheetname "/SoM_Power/")
		(sheetfile "som_power.kicad_sch")
		(attr exclude_from_pos_files exclude_from_bom)
		(fp_circle
			(center 0 0)
			(end 0.475 0)
			(stroke
				(width 0.05)
				(type default)
			)
			(fill no)
			(layer "B.CrtYd")
		)
		(fp_text user "Author: Antmicro"
			(at -0.4 -3.901 0)
			(layer "B.Fab")
			(effects
				(font
					(size 0.7 0.7)
					(thickness 0.15)
				)
				(justify left bottom mirror)
			)
		)
		(fp_text user "License: Apache-2.0"
			(at -0.4 -5.101 0)
			(layer "B.Fab")
			(effects
				(font
					(size 0.7 0.7)
					(thickness 0.15)
				)
				(justify left bottom mirror)
			)
		)
		(fp_text user "${REFERENCE}"
			(at -0.4 -2.7 0)
			(layer "B.Fab")
			(effects
				(font
					(size 0.7 0.7)
					(thickness 0.15)
				)
				(justify left bottom mirror)
			)
		)
		(pad "1" smd circle
			(at 0 0 180)
			(size 0.75 0.75)
			(layers "B.Cu" "B.Mask")
			(net 610 "/SoM_Power/~{PWR_BTN}")
			(pinfunction "1")
			(pintype "passive")
		)
	)
)
